(kicad_pcb
	(version 20260206)
	(generator "pcbnew")
	(generator_version "10.0")
	(general
		(thickness 1.6)
		(legacy_teardrops no)
	)
	(paper "A4")
	(title_block
		(title "dpb — 14545-sa.0730WZS0815.brd")
		(comment 1 "Honey Badger (Wiwynn) / footprints 823-829 of 1066")
	)
	(layers
		(0 "F.Cu" signal "TOP")
		(4 "In1.Cu" signal "L2GND")
		(6 "In2.Cu" signal "L3")
		(8 "In3.Cu" signal "L4VCC")
		(10 "In4.Cu" signal "L5VCC")
		(12 "In5.Cu" signal "L6")
		(14 "In6.Cu" signal "L7GND")
		(2 "B.Cu" signal "BOTTOM")
		(9 "F.Adhes" user "F.Adhesive")
		(11 "B.Adhes" user "B.Adhesive")
		(13 "F.Paste" user "Package Geometry/Pastemask Top")
		(15 "B.Paste" user "Package Geometry/Pastemask Bottom")
		(5 "F.SilkS" user "Ref Des/Silkscreen Top")
		(7 "B.SilkS" user "Ref Des/Silkscreen Bottom")
		(1 "F.Mask" user "Board Geometry/Soldermask Top")
		(3 "B.Mask" user "Board Geometry/Soldermask Bottom")
		(17 "Dwgs.User" user "User.Drawings")
		(19 "Cmts.User" user "User.Comments")
		(21 "Eco1.User" user "User.Eco1")
		(23 "Eco2.User" user "User.Eco2")
		(25 "Edge.Cuts" user "Board Geometry/Outline")
		(27 "Margin" user)
		(31 "F.CrtYd" user "Package Geometry/Place Bound Top")
		(29 "B.CrtYd" user "Package Geometry/Place Bound Bottom")
		(35 "F.Fab" user "Ref Des/Assembly Top")
		(33 "B.Fab" user "Ref Des/Assembly Bottom")
	)
	(footprint ""
		(layer "F.Cu")
		(at 31.190946 -376.8217)
		(property "Reference" "C340"
			(at 0 0 0)
			(layer "F.SilkS")
			(hide yes)
			(effects
				(font
					(size 1.27 1.27)
				)
			)
		)
		(property "Value" "SCD1U10V2KX-5GP"
			(at 1.1811 -2.7051 0)
			(unlocked yes)
			(layer "F.Fab")
			(hide yes)
			(effects
				(font
					(size 1.016 1.016)
					(thickness 0.1524)
				)
			)
		)
		(property "Device Type" "C402H22"
			(at 1.1811 -4.2291 0)
			(unlocked yes)
			(layer "F.Fab")
			(hide yes)
			(effects
				(font
					(size 1.016 1.016)
					(thickness 0.1524)
				)
			)
		)
		(duplicate_pad_numbers_are_jumpers no)
		(fp_rect
			(start -0.4318 0.9525)
			(end 0.4318 -0.9525)
			(stroke
				(width 0)
				(type default)
			)
			(fill no)
			(layer "F.CrtYd")
		)
		(fp_rect
			(start -0.4318 0.9525)
			(end 0.4318 -0.9525)
			(stroke
				(width 0)
				(type default)
			)
			(fill no)
			(layer "F.Fab")
		)
		(pad "1" smd custom
			(at 0 -0.4445)
			(size 0.1524 0.1524)
			(layers "F.Cu" "F.Mask" "F.Paste")
			(net "P3V3")
			(options
				(clearance outline)
				(anchor circle)
			)
			(primitives
				(gr_poly
					(pts
						(arc
							(start 0.3048 -0.2032)
							(mid 0.275042 -0.275042)
							(end 0.2032 -0.3048)
						)
						(arc
							(start -0.2032 -0.3048)
							(mid -0.275042 -0.275042)
							(end -0.3048 -0.2032)
						)
						(arc
							(start -0.3048 0.2032)
							(mid -0.275042 0.275042)
							(end -0.2032 0.3048)
						)
						(arc
							(start 0.2032 0.3048)
							(mid 0.275042 0.275042)
							(end 0.3048 0.2032)
						)
					)
					(width 0)
					(fill yes)
				)
			)
		)
		(pad "2" smd custom
			(at 0 0.4445)
			(size 0.1524 0.1524)
			(layers "F.Cu" "F.Mask" "F.Paste")
			(net "GND")
			(options
				(clearance outline)
				(anchor circle)
			)
			(primitives
				(gr_poly
					(pts
						(arc
							(start 0.3048 -0.2032)
							(mid 0.275042 -0.275042)
							(end 0.2032 -0.3048)
						)
						(arc
							(start -0.2032 -0.3048)
							(mid -0.275042 -0.275042)
							(end -0.3048 -0.2032)
						)
						(arc
							(start -0.3048 0.2032)
							(mid -0.275042 0.275042)
							(end -0.2032 0.3048)
						)
						(arc
							(start 0.2032 0.3048)
							(mid 0.275042 0.275042)
							(end 0.3048 0.2032)
						)
					)
					(width 0)
					(fill yes)
				)
			)
		)
	)
	(footprint ""
		(layer "F.Cu")
		(at 82.225134 -494.514886 -90)
		(property "Reference" "U18"
			(at 0 0 270)
			(layer "F.SilkS")
			(hide yes)
			(effects
				(font
					(size 1.27 1.27)
				)
			)
		)
		(property "Value" "74LVC1G08GW-1-GP"
			(at -2.3368 -8.6868 270)
			(unlocked yes)
			(layer "F.Fab")
			(hide yes)
			(effects
				(font
					(size 1.016 1.016)
					(thickness 0.1524)
				)
			)
		)
		(property "Device Type" "SC70-5H44"
			(at -2.3114 -10.414 270)
			(unlocked yes)
			(layer "F.Fab")
			(hide yes)
			(effects
				(font
					(size 1.016 1.016)
					(thickness 0.1524)
				)
			)
		)
		(duplicate_pad_numbers_are_jumpers no)
		(fp_line
			(start -1.27 1.7018)
			(end -1.27 -1.7018)
			(stroke
				(width 0.1524)
				(type default)
			)
			(layer "F.SilkS")
		)
		(fp_line
			(start 1.27 1.7018)
			(end -1.27 1.7018)
			(stroke
				(width 0.1524)
				(type default)
			)
			(layer "F.SilkS")
		)
		(fp_line
			(start -1.27 -1.7018)
			(end 1.27 -1.7018)
			(stroke
				(width 0.1524)
				(type default)
			)
			(layer "F.SilkS")
		)
		(fp_line
			(start 1.27 -1.7018)
			(end 1.27 1.7018)
			(stroke
				(width 0.1524)
				(type default)
			)
			(layer "F.SilkS")
		)
		(fp_line
			(start 0.6604 -1.8034)
			(end 1.3843 -1.8034)
			(stroke
				(width 0.3302)
				(type default)
			)
			(layer "F.SilkS")
		)
		(fp_line
			(start 1.3843 -1.8034)
			(end 1.3843 -1.1176)
			(stroke
				(width 0.3302)
				(type default)
			)
			(layer "F.SilkS")
		)
		(fp_rect
			(start -1.524 1.9558)
			(end 1.524 -1.9558)
			(stroke
				(width 0)
				(type default)
			)
			(fill no)
			(layer "F.CrtYd")
		)
		(fp_poly
			(pts
				(xy -1.524 -1.9558) (xy 1.524 -1.9558) (xy 1.524 1.9558) (xy -1.524 1.9558)
			)
			(stroke
				(width 0)
				(type default)
			)
			(fill no)
			(layer "F.Fab")
		)
		(pad "1" smd rect
			(at 0.65024 -0.8255 270)
			(size 0.4064 1.2192)
			(layers "F.Cu" "F.Mask" "F.Paste")
			(net "SAS_EXP_B_PWR5")
		)
		(pad "2" smd rect
			(at 0 -0.8255 270)
			(size 0.4064 1.2192)
			(layers "F.Cu" "F.Mask" "F.Paste")
			(net "SAS_EXP_A_PWR5")
		)
		(pad "3" smd rect
			(at -0.65024 -0.8255 270)
			(size 0.4064 1.2192)
			(layers "F.Cu" "F.Mask" "F.Paste")
			(net "GND")
		)
		(pad "4" smd rect
			(at -0.65024 0.8255 270)
			(size 0.4064 1.2192)
			(layers "F.Cu" "F.Mask" "F.Paste")
			(net "DRIVE_PWR5")
		)
		(pad "5" smd rect
			(at 0.65024 0.8255 270)
			(size 0.4064 1.2192)
			(layers "F.Cu" "F.Mask" "F.Paste")
			(net "P3V3")
		)
	)
	(footprint ""
		(layer "F.Cu")
		(at 50.545746 -133.124702)
		(property "Reference" "Q27"
			(at 0 0 0)
			(layer "F.SilkS")
			(hide yes)
			(effects
				(font
					(size 1.27 1.27)
				)
			)
		)
		(property "Value" "AO4406AL-GP"
			(at -3.707384 -1.5367 0)
			(unlocked yes)
			(layer "F.Fab")
			(hide yes)
			(effects
				(font
					(size 1.016 1.016)
					(thickness 0.1524)
				)
			)
		)
		(property "Device Type" "SOIC8H69"
			(at -3.707384 -3.0607 0)
			(unlocked yes)
			(layer "F.Fab")
			(hide yes)
			(effects
				(font
					(size 1.016 1.016)
					(thickness 0.1524)
				)
			)
		)
		(duplicate_pad_numbers_are_jumpers no)
		(fp_line
			(start -2.7432 -1.4224)
			(end -2.7432 1.4224)
			(stroke
				(width 0.1524)
				(type default)
			)
			(layer "F.SilkS")
		)
		(fp_line
			(start -2.7432 1.4224)
			(end -2.6416 1.4224)
			(stroke
				(width 0.1524)
				(type default)
			)
			(layer "F.SilkS")
		)
		(fp_line
			(start -2.7432 1.4224)
			(end 2.1336 1.4224)
			(stroke
				(width 0.1524)
				(type default)
			)
			(layer "F.SilkS")
		)
		(fp_line
			(start -2.7178 -0.508)
			(end -2.1844 -0.0508)
			(stroke
				(width 0.1524)
				(type default)
			)
			(layer "F.SilkS")
		)
		(fp_line
			(start -2.6289 3.4417)
			(end -2.6289 1.4732)
			(stroke
				(width 0.381)
				(type default)
			)
			(layer "F.SilkS")
		)
		(fp_line
			(start -2.1844 -0.0508)
			(end -2.7178 0.508)
			(stroke
				(width 0.1524)
				(type default)
			)
			(layer "F.SilkS")
		)
		(fp_line
			(start 2.1336 -1.4224)
			(end -2.7432 -1.4224)
			(stroke
				(width 0.1524)
				(type default)
			)
			(layer "F.SilkS")
		)
		(fp_line
			(start 2.1336 1.4224)
			(end 2.1336 -1.4224)
			(stroke
				(width 0.1524)
				(type default)
			)
			(layer "F.SilkS")
		)
		(fp_poly
			(pts
				(xy -2.2098 -1.4224) (xy -2.2098 1.4224) (xy 2.2098 1.4224) (xy 2.2098 -1.4224)
			)
			(stroke
				(width 0)
				(type default)
			)
			(fill yes)
			(layer "F.SilkS")
		)
		(fp_rect
			(start -2.450084 2.999994)
			(end 2.450084 -2.999994)
			(stroke
				(width 0)
				(type default)
			)
			(fill no)
			(layer "F.CrtYd")
		)
		(fp_poly
			(pts
				(xy -2.8194 3.6322) (xy -2.8194 -3.6322) (xy 2.8194 -3.6322) (xy 2.8194 1.18364) (xy 2.450084 1.18364)
				(xy 2.450084 -2.999994) (xy -2.450084 -2.999994) (xy -2.450084 2.999994) (xy 2.450084 2.999994)
				(xy 2.450084 1.18618) (xy 2.8194 1.18618) (xy 2.8194 3.6322)
			)
			(stroke
				(width 0)
				(type default)
			)
			(fill no)
			(layer "F.CrtYd")
		)
		(fp_rect
			(start -2.8194 3.6322)
			(end 2.8194 -3.6322)
			(stroke
				(width 0)
				(type default)
			)
			(fill no)
			(layer "F.Fab")
		)
		(pad "1" smd rect
			(at -1.905 2.54)
			(size 0.635 1.651)
			(layers "F.Cu" "F.Mask" "F.Paste")
			(net "P5V_HDD13")
		)
		(pad "2" smd rect
			(at -0.635 2.54)
			(size 0.635 1.651)
			(layers "F.Cu" "F.Mask" "F.Paste")
			(net "P5V_HDD13")
		)
		(pad "3" smd rect
			(at 0.635 2.54)
			(size 0.635 1.651)
			(layers "F.Cu" "F.Mask" "F.Paste")
			(net "P5V_HDD13")
		)
		(pad "4" smd rect
			(at 1.905 2.54)
			(size 0.635 1.651)
			(layers "F.Cu" "F.Mask" "F.Paste")
			(net "SW_HDD13_P")
		)
		(pad "5" smd rect
			(at 1.905 -2.54)
			(size 0.635 1.651)
			(layers "F.Cu" "F.Mask" "F.Paste")
			(net "P5VC")
		)
		(pad "6" smd rect
			(at 0.635 -2.54)
			(size 0.635 1.651)
			(layers "F.Cu" "F.Mask" "F.Paste")
			(net "P5VC")
		)
		(pad "7" smd rect
			(at -0.635 -2.54)
			(size 0.635 1.651)
			(layers "F.Cu" "F.Mask" "F.Paste")
			(net "P5VC")
		)
		(pad "8" smd rect
			(at -1.905 -2.54)
			(size 0.635 1.651)
			(layers "F.Cu" "F.Mask" "F.Paste")
			(net "P5VC")
		)
	)
	(footprint ""
		(layer "F.Cu")
		(at 188.988446 -458.377036)
		(property "Reference" "R349"
			(at 0 0 0)
			(layer "F.SilkS")
			(hide yes)
			(effects
				(font
					(size 1.27 1.27)
				)
			)
		)
		(property "Value" "4K7R2J-2-GP"
			(at 0.064008 -3.993896 0)
			(unlocked yes)
			(layer "F.Fab")
			(hide yes)
			(effects
				(font
					(size 1.016 1.016)
					(thickness 0.1524)
				)
			)
		)
		(property "Device Type" "R402H16"
			(at 0.064008 -5.517896 0)
			(unlocked yes)
			(layer "F.Fab")
			(hide yes)
			(effects
				(font
					(size 1.016 1.016)
					(thickness 0.1524)
				)
			)
		)
		(duplicate_pad_numbers_are_jumpers no)
		(fp_line
			(start -0.508 -0.9398)
			(end -0.508 0.9398)
			(stroke
				(width 0.1524)
				(type default)
			)
			(layer "F.SilkS")
		)
		(fp_line
			(start 0.508 -0.9398)
			(end -0.508 -0.9398)
			(stroke
				(width 0.1524)
				(type default)
			)
			(layer "F.SilkS")
		)
		(fp_rect
			(start -0.508 0.9398)
			(end 0.508 -0.9398)
			(stroke
				(width 0)
				(type default)
			)
			(fill no)
			(layer "F.CrtYd")
		)
		(fp_rect
			(start -0.508 0.9398)
			(end 0.508 -0.9398)
			(stroke
				(width 0)
				(type default)
			)
			(fill no)
			(layer "F.Fab")
		)
		(pad "1" smd custom
			(at 0 -0.4445)
			(size 0.1397 0.1397)
			(layers "F.Cu" "F.Mask" "F.Paste")
			(net "EEPROM_A1")
			(options
				(clearance outline)
				(anchor circle)
			)
			(primitives
				(gr_poly
					(pts
						(arc
							(start -0.1778 -0.2794)
							(mid -0.249642 -0.249642)
							(end -0.2794 -0.1778)
						)
						(arc
							(start -0.2794 0.1778)
							(mid -0.249642 0.249642)
							(end -0.1778 0.2794)
						)
						(arc
							(start 0.1778 0.2794)
							(mid 0.249642 0.249642)
							(end 0.2794 0.1778)
						)
						(arc
							(start 0.2794 -0.1778)
							(mid 0.249642 -0.249642)
							(end 0.1778 -0.2794)
						)
					)
					(width 0)
					(fill yes)
				)
			)
		)
		(pad "2" smd custom
			(at 0 0.4445)
			(size 0.1397 0.1397)
			(layers "F.Cu" "F.Mask" "F.Paste")
			(net "GND")
			(options
				(clearance outline)
				(anchor circle)
			)
			(primitives
				(gr_poly
					(pts
						(arc
							(start -0.1778 -0.2794)
							(mid -0.249642 -0.249642)
							(end -0.2794 -0.1778)
						)
						(arc
							(start -0.2794 0.1778)
							(mid -0.249642 0.249642)
							(end -0.1778 0.2794)
						)
						(arc
							(start 0.1778 0.2794)
							(mid 0.249642 0.249642)
							(end 0.2794 0.1778)
						)
						(arc
							(start 0.2794 -0.1778)
							(mid 0.249642 -0.249642)
							(end 0.1778 -0.2794)
						)
					)
					(width 0)
					(fill yes)
				)
			)
		)
	)
	(footprint ""
		(layer "F.Cu")
		(at 229.996746 -31.6357 90)
		(property "Reference" "PC8"
			(at 0 0 90)
			(layer "F.SilkS")
			(hide yes)
			(effects
				(font
					(size 1.27 1.27)
				)
			)
		)
		(property "Value" "SCD1U25V2KX-GP"
			(at 1.1811 -2.7051 90)
			(unlocked yes)
			(layer "F.Fab")
			(hide yes)
			(effects
				(font
					(size 1.016 1.016)
					(thickness 0.1524)
				)
			)
		)
		(property "Device Type" "C402H22"
			(at 1.1811 -4.2291 90)
			(unlocked yes)
			(layer "F.Fab")
			(hide yes)
			(effects
				(font
					(size 1.016 1.016)
					(thickness 0.1524)
				)
			)
		)
		(duplicate_pad_numbers_are_jumpers no)
		(fp_rect
			(start -0.4318 0.9525)
			(end 0.4318 -0.9525)
			(stroke
				(width 0)
				(type default)
			)
			(fill no)
			(layer "F.CrtYd")
		)
		(fp_rect
			(start -0.4318 0.9525)
			(end 0.4318 -0.9525)
			(stroke
				(width 0)
				(type default)
			)
			(fill no)
			(layer "F.Fab")
		)
		(pad "1" smd custom
			(at 0 -0.4445 90)
			(size 0.1524 0.1524)
			(layers "F.Cu" "F.Mask" "F.Paste")
			(net "P5VA")
			(options
				(clearance outline)
				(anchor circle)
			)
			(primitives
				(gr_poly
					(pts
						(arc
							(start 0.3048 -0.2032)
							(mid 0.275042 -0.275042)
							(end 0.2032 -0.3048)
						)
						(arc
							(start -0.2032 -0.3048)
							(mid -0.275042 -0.275042)
							(end -0.3048 -0.2032)
						)
						(arc
							(start -0.3048 0.2032)
							(mid -0.275042 0.275042)
							(end -0.2032 0.3048)
						)
						(arc
							(start 0.2032 0.3048)
							(mid 0.275042 0.275042)
							(end 0.3048 0.2032)
						)
					)
					(width 0)
					(fill yes)
				)
			)
		)
		(pad "2" smd custom
			(at 0 0.4445 90)
			(size 0.1524 0.1524)
			(layers "F.Cu" "F.Mask" "F.Paste")
			(net "P5VA_LL_NET")
			(options
				(clearance outline)
				(anchor circle)
			)
			(primitives
				(gr_poly
					(pts
						(arc
							(start 0.3048 -0.2032)
							(mid 0.275042 -0.275042)
							(end 0.2032 -0.3048)
						)
						(arc
							(start -0.2032 -0.3048)
							(mid -0.275042 -0.275042)
							(end -0.3048 -0.2032)
						)
						(arc
							(start -0.3048 0.2032)
							(mid -0.275042 0.275042)
							(end -0.2032 0.3048)
						)
						(arc
							(start 0.2032 0.3048)
							(mid 0.275042 0.275042)
							(end 0.3048 0.2032)
						)
					)
					(width 0)
					(fill yes)
				)
			)
		)
	)
	(footprint ""
		(layer "F.Cu")
		(at 6.857746 -493.1537 180)
		(property "Reference" "TP21"
			(at 0 0 180)
			(layer "F.SilkS")
			(hide yes)
			(effects
				(font
					(size 1.27 1.27)
				)
			)
		)
		(property "Value" "TPAD32-GP"
			(at 0 -3.166364 180)
			(unlocked yes)
			(layer "F.Fab")
			(hide yes)
			(effects
				(font
					(size 1.016 1.016)
					(thickness 0.1524)
				)
			)
		)
		(property "Device Type" "TPAD32"
			(at 0 -4.690618 180)
			(unlocked yes)
			(layer "F.Fab")
			(hide yes)
			(effects
				(font
					(size 1.016 1.016)
					(thickness 0.1524)
				)
			)
		)
		(duplicate_pad_numbers_are_jumpers no)
		(fp_poly
			(pts
				(arc
					(start -0.4064 0)
					(mid 0.4064 0)
					(end -0.4064 0)
				)
			)
			(stroke
				(width 0)
				(type default)
			)
			(fill no)
			(layer "F.CrtYd")
		)
		(fp_poly
			(pts
				(arc
					(start -0.7112 0)
					(mid 0.7112 0)
					(end -0.7112 0)
				)
			)
			(stroke
				(width 0)
				(type default)
			)
			(fill no)
			(layer "F.Fab")
		)
		(pad "1" smd circle
			(at 0 0 180)
			(size 0.8128 0.8128)
			(layers "F.Cu" "F.Mask" "F.Paste")
			(net "P5VC_EN")
		)
	)
	(footprint ""
		(layer "F.Cu")
		(at 199.855582 -292.453568 -90)
		(property "Reference" "U8"
			(at 0 0 270)
			(layer "F.SilkS")
			(hide yes)
			(effects
				(font
					(size 1.27 1.27)
				)
			)
		)
		(property "Value" "P2003EVG-GP"
			(at 0 -11.1252 270)
			(unlocked yes)
			(layer "F.Fab")
			(hide yes)
			(effects
				(font
					(size 1.016 1.016)
					(thickness 0.1524)
				)
			)
		)
		(property "Device Type" "SOIC8H79"
			(at 0 -12.6492 270)
			(unlocked yes)
			(layer "F.Fab")
			(hide yes)
			(effects
				(font
					(size 1.016 1.016)
					(thickness 0.1524)
				)
			)
		)
		(duplicate_pad_numbers_are_jumpers no)
		(fp_line
			(start -2.6162 3.429)
			(end -2.6162 1.4732)
			(stroke
				(width 0.4064)
				(type default)
			)
			(layer "F.SilkS")
		)
		(fp_line
			(start -2.7432 1.4224)
			(end 2.1336 1.4224)
			(stroke
				(width 0.1524)
				(type default)
			)
			(layer "F.SilkS")
		)
		(fp_line
			(start 2.1336 1.4224)
			(end 2.1336 -1.4224)
			(stroke
				(width 0.1524)
				(type default)
			)
			(layer "F.SilkS")
		)
		(fp_line
			(start -2.2352 0)
			(end -2.7432 0.508)
			(stroke
				(width 0.1524)
				(type default)
			)
			(layer "F.SilkS")
		)
		(fp_line
			(start -2.7432 -0.508)
			(end -2.2352 0)
			(stroke
				(width 0.1524)
				(type default)
			)
			(layer "F.SilkS")
		)
		(fp_line
			(start -2.7432 -1.4224)
			(end -2.7432 1.4224)
			(stroke
				(width 0.1524)
				(type default)
			)
			(layer "F.SilkS")
		)
		(fp_line
			(start 2.1336 -1.4224)
			(end -2.7432 -1.4224)
			(stroke
				(width 0.1524)
				(type default)
			)
			(layer "F.SilkS")
		)
		(fp_poly
			(pts
				(xy 2.2098 -1.4224) (xy 2.2098 1.4224) (xy -2.2225 1.4224) (xy -2.2225 -1.4224)
			)
			(stroke
				(width 0)
				(type default)
			)
			(fill yes)
			(layer "F.SilkS")
		)
		(fp_rect
			(start -2.4511 2.9972)
			(end 2.4511 -2.9972)
			(stroke
				(width 0)
				(type default)
			)
			(fill no)
			(layer "F.CrtYd")
		)
		(fp_poly
			(pts
				(xy -2.8194 3.6322) (xy -2.8194 -3.6322) (xy 2.8194 -3.6322) (xy 2.8194 -2.2987) (xy 2.4511 -2.2987)
				(xy 2.4511 -2.9972) (xy -2.4511 -2.9972) (xy -2.4511 2.9972) (xy 2.4511 2.9972) (xy 2.4511 -2.286)
				(xy 2.8194 -2.286) (xy 2.8194 3.6322)
			)
			(stroke
				(width 0)
				(type default)
			)
			(fill no)
			(layer "F.CrtYd")
		)
		(fp_rect
			(start -2.8194 3.6322)
			(end 2.8194 -3.6322)
			(stroke
				(width 0)
				(type default)
			)
			(fill no)
			(layer "F.Fab")
		)
		(pad "1" smd rect
			(at -1.905 2.54 270)
			(size 0.635 1.651)
			(layers "F.Cu" "F.Mask" "F.Paste")
			(net "P12V")
		)
		(pad "2" smd rect
			(at -0.635 2.54 270)
			(size 0.635 1.651)
			(layers "F.Cu" "F.Mask" "F.Paste")
			(net "P12V")
		)
		(pad "3" smd rect
			(at 0.635 2.54 270)
			(size 0.635 1.651)
			(layers "F.Cu" "F.Mask" "F.Paste")
			(net "P12V")
		)
		(pad "4" smd rect
			(at 1.905 2.54 270)
			(size 0.635 1.651)
			(layers "F.Cu" "F.Mask" "F.Paste")
			(net "SW_HDD2_N")
		)
		(pad "5" smd rect
			(at 1.905 -2.54 270)
			(size 0.635 1.651)
			(layers "F.Cu" "F.Mask" "F.Paste")
			(net "P12V_HDD2")
		)
		(pad "6" smd rect
			(at 0.635 -2.54 270)
			(size 0.635 1.651)
			(layers "F.Cu" "F.Mask" "F.Paste")
			(net "P12V_HDD2")
		)
		(pad "7" smd rect
			(at -0.635 -2.54 270)
			(size 0.635 1.651)
			(layers "F.Cu" "F.Mask" "F.Paste")
			(net "P12V_HDD2")
		)
		(pad "8" smd rect
			(at -1.905 -2.54 270)
			(size 0.635 1.651)
			(layers "F.Cu" "F.Mask" "F.Paste")
			(net "P12V_HDD2")
		)
	)
)
